FILE_TYPE = MACRO_DRAWING;
SET COLOR_WIRE YELLOW;
SET COLOR_PROP ORANGE;
SET COLOR_DOT WHITE;
SET COLOR_ARC YELLOW;
SET COLOR_BODY GREEN;
SET COLOR_NOTE PURPLE;
SET PROP_DISPLAY VALUE;
SET PAGE_NUMBER P381;
FORCEADD TAP..1
(-6975 4725);
FORCEPROP 3 LASTPIN (-7025 4725) SIG_NAME P5E_CPU0_P0_TX_C_DN<13>
J 0
(-7015 4735);
DISPLAY 0.659574 (-7015 4735);
PAINT MONO (-7015 4735);
DISPLAY INVISIBLE (-7015 4735);
FORCEPROP 1 LASTPIN (-7025 4725) BN 13
J 0
(-7037 4733);
DISPLAY 0.680851 (-7037 4733);
PAINT GREEN (-7037 4733);
FORCEPROP 2 LAST CDS_LIB standard
J 0
(-6975 4725);
DISPLAY INVISIBLE (-6975 4725);
FORCEPROP 1 LAST BODY_TYPE PLUMBING
J 0
(-6975 4775);
DISPLAY 0.872340 (-6975 4775);
PAINT GREEN (-6975 4775);
DISPLAY INVISIBLE (-6975 4775);
FORCEPROP 1 LAST HDL_TAP TRUE
J 0
(-6650 4600);
DISPLAY 0.872340 (-6650 4600);
DISPLAY INVISIBLE (-6650 4600);
FORCEPROP 1 LAST PATH I10
J 0
(-6977 4725);
DISPLAY 0.872340 (-6977 4725);
PAINT GREEN (-6977 4725);
DISPLAY INVISIBLE (-6977 4725);
FORCEADD TAP..1
(-6975 5175);
FORCEPROP 3 LASTPIN (-7025 5175) SIG_NAME P5E_CPU0_P0_TX_C_DN<14>
J 0
(-7015 5185);
DISPLAY 0.659574 (-7015 5185);
PAINT MONO (-7015 5185);
DISPLAY INVISIBLE (-7015 5185);
FORCEPROP 1 LASTPIN (-7025 5175) BN 14
J 0
(-7037 5183);
DISPLAY 0.680851 (-7037 5183);
PAINT GREEN (-7037 5183);
FORCEPROP 2 LAST CDS_LIB standard
J 0
(-6975 5175);
DISPLAY INVISIBLE (-6975 5175);
FORCEPROP 1 LAST BODY_TYPE PLUMBING
J 0
(-6975 5225);
DISPLAY 0.872340 (-6975 5225);
PAINT GREEN (-6975 5225);
DISPLAY INVISIBLE (-6975 5225);
FORCEPROP 1 LAST HDL_TAP TRUE
J 0
(-6650 5050);
DISPLAY 0.872340 (-6650 5050);
DISPLAY INVISIBLE (-6650 5050);
FORCEPROP 1 LAST PATH I11
J 0
(-6977 5175);
DISPLAY 0.872340 (-6977 5175);
PAINT GREEN (-6977 5175);
DISPLAY INVISIBLE (-6977 5175);
FORCEADD TAP..1
(-6975 5525);
FORCEPROP 3 LASTPIN (-7025 5525) SIG_NAME P5E_CPU0_P0_TX_C_DN<15>
J 0
(-7015 5535);
DISPLAY 0.659574 (-7015 5535);
PAINT MONO (-7015 5535);
DISPLAY INVISIBLE (-7015 5535);
FORCEPROP 1 LASTPIN (-7025 5525) BN 15
J 0
(-7037 5533);
DISPLAY 0.680851 (-7037 5533);
PAINT GREEN (-7037 5533);
FORCEPROP 2 LAST CDS_LIB standard
J 0
(-6975 5525);
DISPLAY INVISIBLE (-6975 5525);
FORCEPROP 1 LAST BODY_TYPE PLUMBING
J 0
(-6975 5575);
DISPLAY 0.872340 (-6975 5575);
PAINT GREEN (-6975 5575);
DISPLAY INVISIBLE (-6975 5575);
FORCEPROP 1 LAST HDL_TAP TRUE
J 0
(-6650 5400);
DISPLAY 0.872340 (-6650 5400);
DISPLAY INVISIBLE (-6650 5400);
FORCEPROP 1 LAST PATH I12
J 0
(-6977 5525);
DISPLAY 0.872340 (-6977 5525);
PAINT GREEN (-6977 5525);
DISPLAY INVISIBLE (-6977 5525);
FORCEADD TAP..1
(-6775 2975);
FORCEPROP 3 LASTPIN (-6825 2975) SIG_NAME P5E_CPU0_P0_TX_C_DP<8>
J 0
(-6815 2985);
DISPLAY 0.659574 (-6815 2985);
PAINT MONO (-6815 2985);
DISPLAY INVISIBLE (-6815 2985);
FORCEPROP 1 LASTPIN (-6825 2975) BN 8
J 0
(-6837 2983);
DISPLAY 0.680851 (-6837 2983);
PAINT GREEN (-6837 2983);
FORCEPROP 2 LAST CDS_LIB standard
J 0
(-6775 2975);
DISPLAY INVISIBLE (-6775 2975);
FORCEPROP 1 LAST BODY_TYPE PLUMBING
J 0
(-6775 3025);
DISPLAY 0.872340 (-6775 3025);
PAINT GREEN (-6775 3025);
DISPLAY INVISIBLE (-6775 3025);
FORCEPROP 1 LAST HDL_TAP TRUE
J 0
(-6450 2850);
DISPLAY 0.872340 (-6450 2850);
DISPLAY INVISIBLE (-6450 2850);
FORCEPROP 1 LAST PATH I13
J 0
(-6777 2975);
DISPLAY 0.872340 (-6777 2975);
PAINT GREEN (-6777 2975);
DISPLAY INVISIBLE (-6777 2975);
FORCEADD TAP..1
(-6775 3325);
FORCEPROP 3 LASTPIN (-6825 3325) SIG_NAME P5E_CPU0_P0_TX_C_DP<9>
J 0
(-6815 3335);
DISPLAY 0.659574 (-6815 3335);
PAINT MONO (-6815 3335);
DISPLAY INVISIBLE (-6815 3335);
FORCEPROP 1 LASTPIN (-6825 3325) BN 9
J 0
(-6837 3333);
DISPLAY 0.680851 (-6837 3333);
PAINT GREEN (-6837 3333);
FORCEPROP 2 LAST CDS_LIB standard
J 0
(-6775 3325);
DISPLAY INVISIBLE (-6775 3325);
FORCEPROP 1 LAST BODY_TYPE PLUMBING
J 0
(-6775 3375);
DISPLAY 0.872340 (-6775 3375);
PAINT GREEN (-6775 3375);
DISPLAY INVISIBLE (-6775 3375);
FORCEPROP 1 LAST HDL_TAP TRUE
J 0
(-6450 3200);
DISPLAY 0.872340 (-6450 3200);
DISPLAY INVISIBLE (-6450 3200);
FORCEPROP 1 LAST PATH I14
J 0
(-6777 3325);
DISPLAY 0.872340 (-6777 3325);
PAINT GREEN (-6777 3325);
DISPLAY INVISIBLE (-6777 3325);
FORCEADD TAP..1
(-6775 3675);
FORCEPROP 3 LASTPIN (-6825 3675) SIG_NAME P5E_CPU0_P0_TX_C_DP<10>
J 0
(-6815 3685);
DISPLAY 0.659574 (-6815 3685);
PAINT MONO (-6815 3685);
DISPLAY INVISIBLE (-6815 3685);
FORCEPROP 1 LASTPIN (-6825 3675) BN 10
J 0
(-6837 3683);
DISPLAY 0.680851 (-6837 3683);
PAINT GREEN (-6837 3683);
FORCEPROP 2 LAST CDS_LIB standard
J 0
(-6775 3675);
DISPLAY INVISIBLE (-6775 3675);
FORCEPROP 1 LAST BODY_TYPE PLUMBING
J 0
(-6775 3725);
DISPLAY 0.872340 (-6775 3725);
PAINT GREEN (-6775 3725);
DISPLAY INVISIBLE (-6775 3725);
FORCEPROP 1 LAST HDL_TAP TRUE
J 0
(-6450 3550);
DISPLAY 0.872340 (-6450 3550);
DISPLAY INVISIBLE (-6450 3550);
FORCEPROP 1 LAST PATH I15
J 0
(-6777 3675);
DISPLAY 0.872340 (-6777 3675);
PAINT GREEN (-6777 3675);
DISPLAY INVISIBLE (-6777 3675);
FORCEADD TAP..1
(-6775 4025);
FORCEPROP 3 LASTPIN (-6825 4025) SIG_NAME P5E_CPU0_P0_TX_C_DP<11>
J 0
(-6815 4035);
DISPLAY 0.659574 (-6815 4035);
PAINT MONO (-6815 4035);
DISPLAY INVISIBLE (-6815 4035);
FORCEPROP 1 LASTPIN (-6825 4025) BN 11
J 0
(-6837 4033);
DISPLAY 0.680851 (-6837 4033);
PAINT GREEN (-6837 4033);
FORCEPROP 2 LAST CDS_LIB standard
J 0
(-6775 4025);
DISPLAY INVISIBLE (-6775 4025);
FORCEPROP 1 LAST BODY_TYPE PLUMBING
J 0
(-6775 4075);
DISPLAY 0.872340 (-6775 4075);
PAINT GREEN (-6775 4075);
DISPLAY INVISIBLE (-6775 4075);
FORCEPROP 1 LAST HDL_TAP TRUE
J 0
(-6450 3900);
DISPLAY 0.872340 (-6450 3900);
DISPLAY INVISIBLE (-6450 3900);
FORCEPROP 1 LAST PATH I16
J 0
(-6777 4025);
DISPLAY 0.872340 (-6777 4025);
PAINT GREEN (-6777 4025);
DISPLAY INVISIBLE (-6777 4025);
FORCEADD TAP..1
(-6775 4375);
FORCEPROP 3 LASTPIN (-6825 4375) SIG_NAME P5E_CPU0_P0_TX_C_DP<12>
J 0
(-6815 4385);
DISPLAY 0.659574 (-6815 4385);
PAINT MONO (-6815 4385);
DISPLAY INVISIBLE (-6815 4385);
FORCEPROP 1 LASTPIN (-6825 4375) BN 12
J 0
(-6837 4383);
DISPLAY 0.680851 (-6837 4383);
PAINT GREEN (-6837 4383);
FORCEPROP 2 LAST CDS_LIB standard
J 0
(-6775 4375);
DISPLAY INVISIBLE (-6775 4375);
FORCEPROP 1 LAST BODY_TYPE PLUMBING
J 0
(-6775 4425);
DISPLAY 0.872340 (-6775 4425);
PAINT GREEN (-6775 4425);
DISPLAY INVISIBLE (-6775 4425);
FORCEPROP 1 LAST HDL_TAP TRUE
J 0
(-6450 4250);
DISPLAY 0.872340 (-6450 4250);
DISPLAY INVISIBLE (-6450 4250);
FORCEPROP 1 LAST PATH I17
J 0
(-6777 4375);
DISPLAY 0.872340 (-6777 4375);
PAINT GREEN (-6777 4375);
DISPLAY INVISIBLE (-6777 4375);
FORCEADD TAP..1
(-6775 4825);
FORCEPROP 3 LASTPIN (-6825 4825) SIG_NAME P5E_CPU0_P0_TX_C_DP<13>
J 0
(-6815 4835);
DISPLAY 0.659574 (-6815 4835);
PAINT MONO (-6815 4835);
DISPLAY INVISIBLE (-6815 4835);
FORCEPROP 1 LASTPIN (-6825 4825) BN 13
J 0
(-6837 4833);
DISPLAY 0.680851 (-6837 4833);
PAINT GREEN (-6837 4833);
FORCEPROP 2 LAST CDS_LIB standard
J 0
(-6775 4825);
DISPLAY INVISIBLE (-6775 4825);
FORCEPROP 1 LAST BODY_TYPE PLUMBING
J 0
(-6775 4875);
DISPLAY 0.872340 (-6775 4875);
PAINT GREEN (-6775 4875);
DISPLAY INVISIBLE (-6775 4875);
FORCEPROP 1 LAST HDL_TAP TRUE
J 0
(-6450 4700);
DISPLAY 0.872340 (-6450 4700);
DISPLAY INVISIBLE (-6450 4700);
FORCEPROP 1 LAST PATH I18
J 0
(-6777 4825);
DISPLAY 0.872340 (-6777 4825);
PAINT GREEN (-6777 4825);
DISPLAY INVISIBLE (-6777 4825);
FORCEADD TAP..1
(-6775 5075);
FORCEPROP 3 LASTPIN (-6825 5075) SIG_NAME P5E_CPU0_P0_TX_C_DP<14>
J 0
(-6815 5085);
DISPLAY 0.659574 (-6815 5085);
PAINT MONO (-6815 5085);
DISPLAY INVISIBLE (-6815 5085);
FORCEPROP 1 LASTPIN (-6825 5075) BN 14
J 0
(-6837 5083);
DISPLAY 0.680851 (-6837 5083);
PAINT GREEN (-6837 5083);
FORCEPROP 2 LAST CDS_LIB standard
J 0
(-6775 5075);
DISPLAY INVISIBLE (-6775 5075);
FORCEPROP 1 LAST BODY_TYPE PLUMBING
J 0
(-6775 5125);
DISPLAY 0.872340 (-6775 5125);
PAINT GREEN (-6775 5125);
DISPLAY INVISIBLE (-6775 5125);
FORCEPROP 1 LAST HDL_TAP TRUE
J 0
(-6450 4950);
DISPLAY 0.872340 (-6450 4950);
DISPLAY INVISIBLE (-6450 4950);
FORCEPROP 1 LAST PATH I19
J 0
(-6777 5075);
DISPLAY 0.872340 (-6777 5075);
PAINT GREEN (-6777 5075);
DISPLAY INVISIBLE (-6777 5075);
FORCEADD TAP..1
(-6775 5425);
FORCEPROP 3 LASTPIN (-6825 5425) SIG_NAME P5E_CPU0_P0_TX_C_DP<15>
J 0
(-6815 5435);
DISPLAY 0.659574 (-6815 5435);
PAINT MONO (-6815 5435);
DISPLAY INVISIBLE (-6815 5435);
FORCEPROP 1 LASTPIN (-6825 5425) BN 15
J 0
(-6837 5433);
DISPLAY 0.680851 (-6837 5433);
PAINT GREEN (-6837 5433);
FORCEPROP 2 LAST CDS_LIB standard
J 0
(-6775 5425);
DISPLAY INVISIBLE (-6775 5425);
FORCEPROP 1 LAST BODY_TYPE PLUMBING
J 0
(-6775 5475);
DISPLAY 0.872340 (-6775 5475);
PAINT GREEN (-6775 5475);
DISPLAY INVISIBLE (-6775 5475);
FORCEPROP 1 LAST HDL_TAP TRUE
J 0
(-6450 5300);
DISPLAY 0.872340 (-6450 5300);
DISPLAY INVISIBLE (-6450 5300);
FORCEPROP 1 LAST PATH I20
J 0
(-6777 5425);
DISPLAY 0.872340 (-6777 5425);
PAINT GREEN (-6777 5425);
DISPLAY INVISIBLE (-6777 5425);
FORCEADD OFFPAGE..1
R 2
(-5775 5550);
FORCEPROP 2 LAST $XR0 63 
J 0
(-5589 5550);
DISPLAY 0.638298 (-5589 5550);
PAINT MONO (-5589 5550);
FORCEPROP 2 LAST CDS_LIB standard
J 2
(-5775 5550);
DISPLAY INVISIBLE (-5775 5550);
FORCEPROP 1 LAST OFFPAGE TRUE
J 2
(-6100 5425);
DISPLAY 0.872340 (-6100 5425);
DISPLAY INVISIBLE (-6100 5425);
FORCEPROP 1 LAST COMMENT_BODY TRUE
J 2
(-5900 5450);
DISPLAY 0.872340 (-5900 5450);
PAINT GREEN (-5900 5450);
DISPLAY INVISIBLE (-5900 5450);
FORCEPROP 2 LAST PATH I21
J 2
(-5825 5625);
DISPLAY 0.680851 (-5825 5625);
DISPLAY INVISIBLE (-5825 5625);
FORCEADD OFFPAGE..1
R 2
(-5775 5450);
FORCEPROP 2 LAST $XR0 63 
J 0
(-5589 5450);
DISPLAY 0.638298 (-5589 5450);
PAINT MONO (-5589 5450);
FORCEPROP 2 LAST CDS_LIB standard
J 0
(-5775 5450);
DISPLAY INVISIBLE (-5775 5450);
FORCEPROP 1 LAST OFFPAGE TRUE
J 2
(-6100 5325);
DISPLAY 0.872340 (-6100 5325);
DISPLAY INVISIBLE (-6100 5325);
FORCEPROP 1 LAST COMMENT_BODY TRUE
J 2
(-5900 5350);
DISPLAY 0.872340 (-5900 5350);
PAINT GREEN (-5900 5350);
DISPLAY INVISIBLE (-5900 5350);
FORCEPROP 2 LAST PATH I22
J 0
(-5600 5525);
DISPLAY 0.680851 (-5600 5525);
DISPLAY INVISIBLE (-5600 5525);
FORCEADD TAP..1
(-2150 3975);
FORCEPROP 3 LASTPIN (-2200 3975) SIG_NAME P5E_CPU0_P0_TX_C_DP<3>
J 0
(-2190 3985);
DISPLAY 0.659574 (-2190 3985);
PAINT MONO (-2190 3985);
DISPLAY INVISIBLE (-2190 3985);
FORCEPROP 1 LASTPIN (-2200 3975) BN 3
J 0
(-2212 3983);
DISPLAY 0.680851 (-2212 3983);
PAINT GREEN (-2212 3983);
FORCEPROP 2 LAST CDS_LIB standard
J 0
(-2150 3975);
DISPLAY INVISIBLE (-2150 3975);
FORCEPROP 1 LAST BODY_TYPE PLUMBING
J 0
(-2150 4025);
DISPLAY 0.872340 (-2150 4025);
PAINT GREEN (-2150 4025);
DISPLAY INVISIBLE (-2150 4025);
FORCEPROP 1 LAST HDL_TAP TRUE
J 0
(-1825 3850);
DISPLAY 0.872340 (-1825 3850);
DISPLAY INVISIBLE (-1825 3850);
FORCEPROP 1 LAST PATH I23
J 0
(-2152 3975);
DISPLAY 0.872340 (-2152 3975);
PAINT GREEN (-2152 3975);
DISPLAY INVISIBLE (-2152 3975);
FORCEADD TAP..1
(-2350 3725);
FORCEPROP 3 LASTPIN (-2400 3725) SIG_NAME P5E_CPU0_P0_TX_C_DN<2>
J 0
(-2390 3735);
DISPLAY 0.659574 (-2390 3735);
PAINT MONO (-2390 3735);
DISPLAY INVISIBLE (-2390 3735);
FORCEPROP 1 LASTPIN (-2400 3725) BN 2
J 0
(-2412 3733);
DISPLAY 0.680851 (-2412 3733);
PAINT GREEN (-2412 3733);
FORCEPROP 2 LAST CDS_LIB standard
J 0
(-2350 3725);
DISPLAY INVISIBLE (-2350 3725);
FORCEPROP 1 LAST BODY_TYPE PLUMBING
J 0
(-2350 3775);
DISPLAY 0.872340 (-2350 3775);
PAINT GREEN (-2350 3775);
DISPLAY INVISIBLE (-2350 3775);
FORCEPROP 1 LAST HDL_TAP TRUE
J 0
(-2025 3600);
DISPLAY 0.872340 (-2025 3600);
DISPLAY INVISIBLE (-2025 3600);
FORCEPROP 1 LAST PATH I24
J 0
(-2352 3725);
DISPLAY 0.872340 (-2352 3725);
PAINT GREEN (-2352 3725);
DISPLAY INVISIBLE (-2352 3725);
FORCEADD OFFPAGE..1
R 2
(-1150 5400);
FORCEPROP 2 LAST $XR0 63 
J 0
(-964 5400);
DISPLAY 0.638298 (-964 5400);
PAINT MONO (-964 5400);
FORCEPROP 2 LAST CDS_LIB standard
J 0
(-1150 5400);
DISPLAY INVISIBLE (-1150 5400);
FORCEPROP 1 LAST OFFPAGE TRUE
J 2
(-1475 5275);
DISPLAY 0.872340 (-1475 5275);
DISPLAY INVISIBLE (-1475 5275);
FORCEPROP 1 LAST COMMENT_BODY TRUE
J 2
(-1275 5300);
DISPLAY 0.872340 (-1275 5300);
PAINT GREEN (-1275 5300);
DISPLAY INVISIBLE (-1275 5300);
FORCEPROP 2 LAST PATH I25
J 0
(-975 5475);
DISPLAY 0.680851 (-975 5475);
DISPLAY INVISIBLE (-975 5475);
FORCEADD OFFPAGE..1
R 2
(-1150 5500);
FORCEPROP 2 LAST $XR0 63 
J 0
(-964 5500);
DISPLAY 0.638298 (-964 5500);
PAINT MONO (-964 5500);
FORCEPROP 2 LAST CDS_LIB standard
J 2
(-1150 5500);
DISPLAY INVISIBLE (-1150 5500);
FORCEPROP 1 LAST OFFPAGE TRUE
J 2
(-1475 5375);
DISPLAY 0.872340 (-1475 5375);
DISPLAY INVISIBLE (-1475 5375);
FORCEPROP 1 LAST COMMENT_BODY TRUE
J 2
(-1275 5400);
DISPLAY 0.872340 (-1275 5400);
PAINT GREEN (-1275 5400);
DISPLAY INVISIBLE (-1275 5400);
FORCEPROP 2 LAST PATH I26
J 0
(-975 5575);
DISPLAY 0.680851 (-975 5575);
DISPLAY INVISIBLE (-975 5575);
FORCEADD TAP..1
(-2150 5375);
FORCEPROP 3 LASTPIN (-2200 5375) SIG_NAME P5E_CPU0_P0_TX_C_DP<7>
J 0
(-2190 5385);
DISPLAY 0.659574 (-2190 5385);
PAINT MONO (-2190 5385);
DISPLAY INVISIBLE (-2190 5385);
FORCEPROP 1 LASTPIN (-2200 5375) BN 7
J 0
(-2212 5383);
DISPLAY 0.680851 (-2212 5383);
PAINT GREEN (-2212 5383);
FORCEPROP 2 LAST CDS_LIB standard
J 0
(-2150 5375);
DISPLAY INVISIBLE (-2150 5375);
FORCEPROP 1 LAST BODY_TYPE PLUMBING
J 0
(-2150 5425);
DISPLAY 0.872340 (-2150 5425);
PAINT GREEN (-2150 5425);
DISPLAY INVISIBLE (-2150 5425);
FORCEPROP 1 LAST HDL_TAP TRUE
J 0
(-1825 5250);
DISPLAY 0.872340 (-1825 5250);
DISPLAY INVISIBLE (-1825 5250);
FORCEPROP 1 LAST PATH I27
J 0
(-2152 5375);
DISPLAY 0.872340 (-2152 5375);
PAINT GREEN (-2152 5375);
DISPLAY INVISIBLE (-2152 5375);
FORCEADD TAP..1
(-2350 5475);
FORCEPROP 3 LASTPIN (-2400 5475) SIG_NAME P5E_CPU0_P0_TX_C_DN<7>
J 0
(-2390 5485);
DISPLAY 0.659574 (-2390 5485);
PAINT MONO (-2390 5485);
DISPLAY INVISIBLE (-2390 5485);
FORCEPROP 1 LASTPIN (-2400 5475) BN 7
J 0
(-2412 5483);
DISPLAY 0.680851 (-2412 5483);
PAINT GREEN (-2412 5483);
FORCEPROP 2 LAST CDS_LIB standard
J 0
(-2350 5475);
DISPLAY INVISIBLE (-2350 5475);
FORCEPROP 1 LAST BODY_TYPE PLUMBING
J 0
(-2350 5525);
DISPLAY 0.872340 (-2350 5525);
PAINT GREEN (-2350 5525);
DISPLAY INVISIBLE (-2350 5525);
FORCEPROP 1 LAST HDL_TAP TRUE
J 0
(-2025 5350);
DISPLAY 0.872340 (-2025 5350);
DISPLAY INVISIBLE (-2025 5350);
FORCEPROP 1 LAST PATH I28
J 0
(-2352 5475);
DISPLAY 0.872340 (-2352 5475);
PAINT GREEN (-2352 5475);
DISPLAY INVISIBLE (-2352 5475);
FORCEADD TAP..1
(-2350 5125);
FORCEPROP 3 LASTPIN (-2400 5125) SIG_NAME P5E_CPU0_P0_TX_C_DN<6>
J 0
(-2390 5135);
DISPLAY 0.659574 (-2390 5135);
PAINT MONO (-2390 5135);
DISPLAY INVISIBLE (-2390 5135);
FORCEPROP 1 LASTPIN (-2400 5125) BN 6
J 0
(-2412 5133);
DISPLAY 0.680851 (-2412 5133);
PAINT GREEN (-2412 5133);
FORCEPROP 2 LAST CDS_LIB standard
J 0
(-2350 5125);
DISPLAY INVISIBLE (-2350 5125);
FORCEPROP 1 LAST BODY_TYPE PLUMBING
J 0
(-2350 5175);
DISPLAY 0.872340 (-2350 5175);
PAINT GREEN (-2350 5175);
DISPLAY INVISIBLE (-2350 5175);
FORCEPROP 1 LAST HDL_TAP TRUE
J 0
(-2025 5000);
DISPLAY 0.872340 (-2025 5000);
DISPLAY INVISIBLE (-2025 5000);
FORCEPROP 1 LAST PATH I29
J 0
(-2352 5125);
DISPLAY 0.872340 (-2352 5125);
PAINT GREEN (-2352 5125);
DISPLAY INVISIBLE (-2352 5125);
FORCEADD PT5161LRS..8
(-8000 4275);
FORCEPROP 1 LAST LOCATION U6010
J 0
(-8350 5900);
DISPLAY 0.723404 (-8350 5900);
PAINT GREEN (-8350 5900);
FORCEPROP 0 LAST $SEC 8
J 0
(-8350 6050);
DISPLAY 0.680851 (-8350 6050);
PAINT MONO (-8350 6050);
DISPLAY INVISIBLE (-8350 6050);
FORCEPROP 0 LAST CDS_SEC 8
J 0
(-8350 6050);
DISPLAY 0.680851 (-8350 6050);
DISPLAY INVISIBLE (-8350 6050);
FORCEPROP 0 LASTPIN (-7550 5425) $PN R35
J 0
(-7540 5435);
DISPLAY 0.680851 (-7540 5435);
PAINT MONO (-7540 5435);
FORCEPROP 0 LASTPIN (-7550 5075) $PN AB35
J 0
(-7540 5085);
DISPLAY 0.680851 (-7540 5085);
PAINT MONO (-7540 5085);
FORCEPROP 0 LASTPIN (-7550 4725) $PN AJ35
J 0
(-7540 4735);
DISPLAY 0.680851 (-7540 4735);
PAINT MONO (-7540 4735);
FORCEPROP 0 LASTPIN (-7550 4375) $PN AT35
J 0
(-7540 4385);
DISPLAY 0.680851 (-7540 4385);
PAINT MONO (-7540 4385);
FORCEPROP 0 LASTPIN (-7550 4025) $PN BC35
J 0
(-7540 4035);
DISPLAY 0.680851 (-7540 4035);
PAINT MONO (-7540 4035);
FORCEPROP 0 LASTPIN (-7550 3675) $PN BK35
J 0
(-7540 3685);
DISPLAY 0.680851 (-7540 3685);
PAINT MONO (-7540 3685);
FORCEPROP 0 LASTPIN (-7550 3325) $PN BU35
J 0
(-7540 3335);
DISPLAY 0.680851 (-7540 3335);
PAINT MONO (-7540 3335);
FORCEPROP 0 LASTPIN (-7550 2975) $PN CD35
J 0
(-7540 2985);
DISPLAY 0.680851 (-7540 2985);
PAINT MONO (-7540 2985);
FORCEPROP 0 LASTPIN (-7550 5525) $PN N34
J 0
(-7540 5535);
DISPLAY 0.680851 (-7540 5535);
PAINT MONO (-7540 5535);
FORCEPROP 0 LASTPIN (-7550 5175) $PN Y34
J 0
(-7540 5185);
DISPLAY 0.680851 (-7540 5185);
PAINT MONO (-7540 5185);
FORCEPROP 0 LASTPIN (-7550 4825) $PN AG34
J 0
(-7540 4835);
DISPLAY 0.680851 (-7540 4835);
PAINT MONO (-7540 4835);
FORCEPROP 0 LASTPIN (-7550 4475) $PN AP34
J 0
(-7540 4485);
DISPLAY 0.680851 (-7540 4485);
PAINT MONO (-7540 4485);
FORCEPROP 0 LASTPIN (-7550 4125) $PN BA34
J 0
(-7540 4135);
DISPLAY 0.680851 (-7540 4135);
PAINT MONO (-7540 4135);
FORCEPROP 0 LASTPIN (-7550 3775) $PN BH34
J 0
(-7540 3785);
DISPLAY 0.680851 (-7540 3785);
PAINT MONO (-7540 3785);
FORCEPROP 0 LASTPIN (-7550 3425) $PN BR34
J 0
(-7540 3435);
DISPLAY 0.680851 (-7540 3435);
PAINT MONO (-7540 3435);
FORCEPROP 0 LASTPIN (-7550 3075) $PN CB34
J 0
(-7540 3085);
DISPLAY 0.680851 (-7540 3085);
PAINT MONO (-7540 3085);
FORCEPROP 1 LAST MATERIAL IC
J 0
(-8350 5750);
DISPLAY 0.723404 (-8350 5750);
PAINT GREEN (-8350 5750);
FORCEPROP 2 LAST VALUE PT5161LRS
J 0
(-8350 5950);
DISPLAY 0.680851 (-8350 5950);
FORCEPROP 2 LAST PART_TYPE SMLF
J 0
(-8350 6000);
DISPLAY 0.680851 (-8350 6000);
FORCEPROP 1 LAST NEEDS_NO_SIZE TRUE
J 0
(-8000 4275);
DISPLAY 0.723404 (-8000 4275);
PAINT GREEN (-8000 4275);
DISPLAY INVISIBLE (-8000 4275);
FORCEPROP 1 LAST CDS_LMAN_SYM_OUTLINE -350,1450,300,-1400
J 0
(-8000 4275);
DISPLAY 0.468085 (-8000 4275);
PAINT GREEN (-8000 4275);
DISPLAY INVISIBLE (-8000 4275);
FORCEPROP 2 LAST CDS_LIB pure_quanta
J 0
(-8000 4275);
DISPLAY INVISIBLE (-8000 4275);
FORCEPROP 1 LAST PATH I3
J 0
(-8000 4275);
DISPLAY 0.723404 (-8000 4275);
PAINT GREEN (-8000 4275);
DISPLAY INVISIBLE (-8000 4275);
FORCEPROP 1 LAST PART_NUMBER AJ051610U03
J 0
(-8350 5825);
DISPLAY 0.723404 (-8350 5825);
PAINT GREEN (-8350 5825);
DISPLAY INVISIBLE (-8350 5825);
FORCEADD TAP..1
(-2150 5025);
FORCEPROP 3 LASTPIN (-2200 5025) SIG_NAME P5E_CPU0_P0_TX_C_DP<6>
J 0
(-2190 5035);
DISPLAY 0.659574 (-2190 5035);
PAINT MONO (-2190 5035);
DISPLAY INVISIBLE (-2190 5035);
FORCEPROP 1 LASTPIN (-2200 5025) BN 6
J 0
(-2212 5033);
DISPLAY 0.680851 (-2212 5033);
PAINT GREEN (-2212 5033);
FORCEPROP 2 LAST CDS_LIB standard
J 0
(-2150 5025);
DISPLAY INVISIBLE (-2150 5025);
FORCEPROP 1 LAST BODY_TYPE PLUMBING
J 0
(-2150 5075);
DISPLAY 0.872340 (-2150 5075);
PAINT GREEN (-2150 5075);
DISPLAY INVISIBLE (-2150 5075);
FORCEPROP 1 LAST HDL_TAP TRUE
J 0
(-1825 4900);
DISPLAY 0.872340 (-1825 4900);
DISPLAY INVISIBLE (-1825 4900);
FORCEPROP 1 LAST PATH I30
J 0
(-2152 5025);
DISPLAY 0.872340 (-2152 5025);
PAINT GREEN (-2152 5025);
DISPLAY INVISIBLE (-2152 5025);
FORCEADD TAP..1
(-2150 4675);
FORCEPROP 3 LASTPIN (-2200 4675) SIG_NAME P5E_CPU0_P0_TX_C_DP<5>
J 0
(-2190 4685);
DISPLAY 0.659574 (-2190 4685);
PAINT MONO (-2190 4685);
DISPLAY INVISIBLE (-2190 4685);
FORCEPROP 1 LASTPIN (-2200 4675) BN 5
J 0
(-2212 4683);
DISPLAY 0.680851 (-2212 4683);
PAINT GREEN (-2212 4683);
FORCEPROP 2 LAST CDS_LIB standard
J 0
(-2150 4675);
DISPLAY INVISIBLE (-2150 4675);
FORCEPROP 1 LAST BODY_TYPE PLUMBING
J 0
(-2150 4725);
DISPLAY 0.872340 (-2150 4725);
PAINT GREEN (-2150 4725);
DISPLAY INVISIBLE (-2150 4725);
FORCEPROP 1 LAST HDL_TAP TRUE
J 0
(-1825 4550);
DISPLAY 0.872340 (-1825 4550);
DISPLAY INVISIBLE (-1825 4550);
FORCEPROP 1 LAST PATH I31
J 0
(-2152 4675);
DISPLAY 0.872340 (-2152 4675);
PAINT GREEN (-2152 4675);
DISPLAY INVISIBLE (-2152 4675);
FORCEADD TAP..1
(-2350 4775);
FORCEPROP 3 LASTPIN (-2400 4775) SIG_NAME P5E_CPU0_P0_TX_C_DN<5>
J 0
(-2390 4785);
DISPLAY 0.659574 (-2390 4785);
PAINT MONO (-2390 4785);
DISPLAY INVISIBLE (-2390 4785);
FORCEPROP 1 LASTPIN (-2400 4775) BN 5
J 0
(-2412 4783);
DISPLAY 0.680851 (-2412 4783);
PAINT GREEN (-2412 4783);
FORCEPROP 2 LAST CDS_LIB standard
J 0
(-2350 4775);
DISPLAY INVISIBLE (-2350 4775);
FORCEPROP 1 LAST BODY_TYPE PLUMBING
J 0
(-2350 4825);
DISPLAY 0.872340 (-2350 4825);
PAINT GREEN (-2350 4825);
DISPLAY INVISIBLE (-2350 4825);
FORCEPROP 1 LAST HDL_TAP TRUE
J 0
(-2025 4650);
DISPLAY 0.872340 (-2025 4650);
DISPLAY INVISIBLE (-2025 4650);
FORCEPROP 1 LAST PATH I32
J 0
(-2352 4775);
DISPLAY 0.872340 (-2352 4775);
PAINT GREEN (-2352 4775);
DISPLAY INVISIBLE (-2352 4775);
FORCEADD TAP..1
(-2150 4325);
FORCEPROP 3 LASTPIN (-2200 4325) SIG_NAME P5E_CPU0_P0_TX_C_DP<4>
J 0
(-2190 4335);
DISPLAY 0.659574 (-2190 4335);
PAINT MONO (-2190 4335);
DISPLAY INVISIBLE (-2190 4335);
FORCEPROP 1 LASTPIN (-2200 4325) BN 4
J 0
(-2212 4333);
DISPLAY 0.680851 (-2212 4333);
PAINT GREEN (-2212 4333);
FORCEPROP 2 LAST CDS_LIB standard
J 0
(-2150 4325);
DISPLAY INVISIBLE (-2150 4325);
FORCEPROP 1 LAST BODY_TYPE PLUMBING
J 0
(-2150 4375);
DISPLAY 0.872340 (-2150 4375);
PAINT GREEN (-2150 4375);
DISPLAY INVISIBLE (-2150 4375);
FORCEPROP 1 LAST HDL_TAP TRUE
J 0
(-1825 4200);
DISPLAY 0.872340 (-1825 4200);
DISPLAY INVISIBLE (-1825 4200);
FORCEPROP 1 LAST PATH I33
J 0
(-2152 4325);
DISPLAY 0.872340 (-2152 4325);
PAINT GREEN (-2152 4325);
DISPLAY INVISIBLE (-2152 4325);
FORCEADD TAP..1
(-2350 4425);
FORCEPROP 3 LASTPIN (-2400 4425) SIG_NAME P5E_CPU0_P0_TX_C_DN<4>
J 0
(-2390 4435);
DISPLAY 0.659574 (-2390 4435);
PAINT MONO (-2390 4435);
DISPLAY INVISIBLE (-2390 4435);
FORCEPROP 1 LASTPIN (-2400 4425) BN 4
J 0
(-2412 4433);
DISPLAY 0.680851 (-2412 4433);
PAINT GREEN (-2412 4433);
FORCEPROP 2 LAST CDS_LIB standard
J 0
(-2350 4425);
DISPLAY INVISIBLE (-2350 4425);
FORCEPROP 1 LAST BODY_TYPE PLUMBING
J 0
(-2350 4475);
DISPLAY 0.872340 (-2350 4475);
PAINT GREEN (-2350 4475);
DISPLAY INVISIBLE (-2350 4475);
FORCEPROP 1 LAST HDL_TAP TRUE
J 0
(-2025 4300);
DISPLAY 0.872340 (-2025 4300);
DISPLAY INVISIBLE (-2025 4300);
FORCEPROP 1 LAST PATH I34
J 0
(-2352 4425);
DISPLAY 0.872340 (-2352 4425);
PAINT GREEN (-2352 4425);
DISPLAY INVISIBLE (-2352 4425);
FORCEADD TAP..1
(-2350 4075);
FORCEPROP 3 LASTPIN (-2400 4075) SIG_NAME P5E_CPU0_P0_TX_C_DN<3>
J 0
(-2390 4085);
DISPLAY 0.659574 (-2390 4085);
PAINT MONO (-2390 4085);
DISPLAY INVISIBLE (-2390 4085);
FORCEPROP 1 LASTPIN (-2400 4075) BN 3
J 0
(-2412 4083);
DISPLAY 0.680851 (-2412 4083);
PAINT GREEN (-2412 4083);
FORCEPROP 2 LAST CDS_LIB standard
J 0
(-2350 4075);
DISPLAY INVISIBLE (-2350 4075);
FORCEPROP 1 LAST BODY_TYPE PLUMBING
J 0
(-2350 4125);
DISPLAY 0.872340 (-2350 4125);
PAINT GREEN (-2350 4125);
DISPLAY INVISIBLE (-2350 4125);
FORCEPROP 1 LAST HDL_TAP TRUE
J 0
(-2025 3950);
DISPLAY 0.872340 (-2025 3950);
DISPLAY INVISIBLE (-2025 3950);
FORCEPROP 1 LAST PATH I35
J 0
(-2352 4075);
DISPLAY 0.872340 (-2352 4075);
PAINT GREEN (-2352 4075);
DISPLAY INVISIBLE (-2352 4075);
FORCEADD TAP..1
(-2150 3625);
FORCEPROP 3 LASTPIN (-2200 3625) SIG_NAME P5E_CPU0_P0_TX_C_DP<2>
J 0
(-2190 3635);
DISPLAY 0.659574 (-2190 3635);
PAINT MONO (-2190 3635);
DISPLAY INVISIBLE (-2190 3635);
FORCEPROP 1 LASTPIN (-2200 3625) BN 2
J 0
(-2212 3633);
DISPLAY 0.680851 (-2212 3633);
PAINT GREEN (-2212 3633);
FORCEPROP 2 LAST CDS_LIB standard
J 0
(-2150 3625);
DISPLAY INVISIBLE (-2150 3625);
FORCEPROP 1 LAST BODY_TYPE PLUMBING
J 0
(-2150 3675);
DISPLAY 0.872340 (-2150 3675);
PAINT GREEN (-2150 3675);
DISPLAY INVISIBLE (-2150 3675);
FORCEPROP 1 LAST HDL_TAP TRUE
J 0
(-1825 3500);
DISPLAY 0.872340 (-1825 3500);
DISPLAY INVISIBLE (-1825 3500);
FORCEPROP 1 LAST PATH I36
J 0
(-2152 3625);
DISPLAY 0.872340 (-2152 3625);
PAINT GREEN (-2152 3625);
DISPLAY INVISIBLE (-2152 3625);
FORCEADD TAP..1
(-2150 3375);
FORCEPROP 3 LASTPIN (-2200 3375) SIG_NAME P5E_CPU0_P0_TX_C_DP<1>
J 0
(-2190 3385);
DISPLAY 0.659574 (-2190 3385);
PAINT MONO (-2190 3385);
DISPLAY INVISIBLE (-2190 3385);
FORCEPROP 1 LASTPIN (-2200 3375) BN 1
J 0
(-2212 3383);
DISPLAY 0.680851 (-2212 3383);
PAINT GREEN (-2212 3383);
FORCEPROP 2 LAST CDS_LIB standard
J 0
(-2150 3375);
DISPLAY INVISIBLE (-2150 3375);
FORCEPROP 1 LAST BODY_TYPE PLUMBING
J 0
(-2150 3425);
DISPLAY 0.872340 (-2150 3425);
PAINT GREEN (-2150 3425);
DISPLAY INVISIBLE (-2150 3425);
FORCEPROP 1 LAST HDL_TAP TRUE
J 0
(-1825 3250);
DISPLAY 0.872340 (-1825 3250);
DISPLAY INVISIBLE (-1825 3250);
FORCEPROP 1 LAST PATH I37
J 0
(-2152 3375);
DISPLAY 0.872340 (-2152 3375);
PAINT GREEN (-2152 3375);
DISPLAY INVISIBLE (-2152 3375);
FORCEADD TAP..1
(-2350 3275);
FORCEPROP 3 LASTPIN (-2400 3275) SIG_NAME P5E_CPU0_P0_TX_C_DN<1>
J 0
(-2390 3285);
DISPLAY 0.659574 (-2390 3285);
PAINT MONO (-2390 3285);
DISPLAY INVISIBLE (-2390 3285);
FORCEPROP 1 LASTPIN (-2400 3275) BN 1
J 0
(-2412 3283);
DISPLAY 0.680851 (-2412 3283);
PAINT GREEN (-2412 3283);
FORCEPROP 2 LAST CDS_LIB standard
J 0
(-2350 3275);
DISPLAY INVISIBLE (-2350 3275);
FORCEPROP 1 LAST BODY_TYPE PLUMBING
J 0
(-2350 3325);
DISPLAY 0.872340 (-2350 3325);
PAINT GREEN (-2350 3325);
DISPLAY INVISIBLE (-2350 3325);
FORCEPROP 1 LAST HDL_TAP TRUE
J 0
(-2025 3150);
DISPLAY 0.872340 (-2025 3150);
DISPLAY INVISIBLE (-2025 3150);
FORCEPROP 1 LAST PATH I38
J 0
(-2352 3275);
DISPLAY 0.872340 (-2352 3275);
PAINT GREEN (-2352 3275);
DISPLAY INVISIBLE (-2352 3275);
FORCEADD TAP..1
(-2350 3025);
FORCEPROP 3 LASTPIN (-2400 3025) SIG_NAME P5E_CPU0_P0_TX_C_DN<0>
J 0
(-2390 3035);
DISPLAY 0.659574 (-2390 3035);
PAINT MONO (-2390 3035);
DISPLAY INVISIBLE (-2390 3035);
FORCEPROP 1 LASTPIN (-2400 3025) BN 0
J 0
(-2412 3033);
DISPLAY 0.680851 (-2412 3033);
PAINT GREEN (-2412 3033);
FORCEPROP 2 LAST CDS_LIB standard
J 0
(-2350 3025);
DISPLAY INVISIBLE (-2350 3025);
FORCEPROP 1 LAST BODY_TYPE PLUMBING
J 0
(-2350 3075);
DISPLAY 0.872340 (-2350 3075);
PAINT GREEN (-2350 3075);
DISPLAY INVISIBLE (-2350 3075);
FORCEPROP 1 LAST HDL_TAP TRUE
J 0
(-2025 2900);
DISPLAY 0.872340 (-2025 2900);
DISPLAY INVISIBLE (-2025 2900);
FORCEPROP 1 LAST PATH I39
J 0
(-2352 3025);
DISPLAY 0.872340 (-2352 3025);
PAINT GREEN (-2352 3025);
DISPLAY INVISIBLE (-2352 3025);
FORCEADD PT5161LRS..9
(-3375 4225);
FORCEPROP 1 LAST LOCATION U6010
J 0
(-3725 5850);
DISPLAY 0.723404 (-3725 5850);
PAINT GREEN (-3725 5850);
FORCEPROP 0 LAST $SEC 9
J 0
(-3725 6000);
DISPLAY 0.680851 (-3725 6000);
PAINT MONO (-3725 6000);
DISPLAY INVISIBLE (-3725 6000);
FORCEPROP 0 LAST CDS_SEC 9
J 0
(-3725 6000);
DISPLAY 0.680851 (-3725 6000);
DISPLAY INVISIBLE (-3725 6000);
FORCEPROP 0 LASTPIN (-2925 5375) $PN CL35
J 0
(-2915 5385);
DISPLAY 0.680851 (-2915 5385);
PAINT MONO (-2915 5385);
FORCEPROP 0 LASTPIN (-2925 5025) $PN CV35
J 0
(-2915 5035);
DISPLAY 0.680851 (-2915 5035);
PAINT MONO (-2915 5035);
FORCEPROP 0 LASTPIN (-2925 4675) $PN DE35
J 0
(-2915 4685);
DISPLAY 0.680851 (-2915 4685);
PAINT MONO (-2915 4685);
FORCEPROP 0 LASTPIN (-2925 4325) $PN DM35
J 0
(-2915 4335);
DISPLAY 0.680851 (-2915 4335);
PAINT MONO (-2915 4335);
FORCEPROP 0 LASTPIN (-2925 3975) $PN DW35
J 0
(-2915 3985);
DISPLAY 0.680851 (-2915 3985);
PAINT MONO (-2915 3985);
FORCEPROP 0 LASTPIN (-2925 3625) $PN EF35
J 0
(-2915 3635);
DISPLAY 0.680851 (-2915 3635);
PAINT MONO (-2915 3635);
FORCEPROP 0 LASTPIN (-2925 3275) $PN EN35
J 0
(-2915 3285);
DISPLAY 0.680851 (-2915 3285);
PAINT MONO (-2915 3285);
FORCEPROP 0 LASTPIN (-2925 2925) $PN EY35
J 0
(-2915 2935);
DISPLAY 0.680851 (-2915 2935);
PAINT MONO (-2915 2935);
FORCEPROP 0 LASTPIN (-2925 5475) $PN CJ34
J 0
(-2915 5485);
DISPLAY 0.680851 (-2915 5485);
PAINT MONO (-2915 5485);
FORCEPROP 0 LASTPIN (-2925 5125) $PN CT34
J 0
(-2915 5135);
DISPLAY 0.680851 (-2915 5135);
PAINT MONO (-2915 5135);
FORCEPROP 0 LASTPIN (-2925 4775) $PN DC34
J 0
(-2915 4785);
DISPLAY 0.680851 (-2915 4785);
PAINT MONO (-2915 4785);
FORCEPROP 0 LASTPIN (-2925 4425) $PN DK34
J 0
(-2915 4435);
DISPLAY 0.680851 (-2915 4435);
PAINT MONO (-2915 4435);
FORCEPROP 0 LASTPIN (-2925 4075) $PN DU34
J 0
(-2915 4085);
DISPLAY 0.680851 (-2915 4085);
PAINT MONO (-2915 4085);
FORCEPROP 0 LASTPIN (-2925 3725) $PN ED34
J 0
(-2915 3735);
DISPLAY 0.680851 (-2915 3735);
PAINT MONO (-2915 3735);
FORCEPROP 0 LASTPIN (-2925 3375) $PN EL34
J 0
(-2915 3385);
DISPLAY 0.680851 (-2915 3385);
PAINT MONO (-2915 3385);
FORCEPROP 0 LASTPIN (-2925 3025) $PN EV34
J 0
(-2915 3035);
DISPLAY 0.680851 (-2915 3035);
PAINT MONO (-2915 3035);
FORCEPROP 2 LAST PART_TYPE SMLF
J 0
(-3725 5950);
DISPLAY 0.680851 (-3725 5950);
FORCEPROP 1 LAST MATERIAL IC
J 0
(-3725 5700);
DISPLAY 0.723404 (-3725 5700);
PAINT GREEN (-3725 5700);
FORCEPROP 2 LAST VALUE PT5161LRS
J 0
(-3725 5900);
DISPLAY 0.680851 (-3725 5900);
FORCEPROP 2 LAST CDS_LIB pure_quanta
J 0
(-3375 4225);
DISPLAY INVISIBLE (-3375 4225);
FORCEPROP 1 LAST CDS_LMAN_SYM_OUTLINE -350,1450,300,-1400
J 0
(-3375 4225);
DISPLAY 0.468085 (-3375 4225);
PAINT GREEN (-3375 4225);
DISPLAY INVISIBLE (-3375 4225);
FORCEPROP 1 LAST NEEDS_NO_SIZE TRUE
J 0
(-3375 4225);
DISPLAY 0.723404 (-3375 4225);
PAINT GREEN (-3375 4225);
DISPLAY INVISIBLE (-3375 4225);
FORCEPROP 1 LAST PATH I4
J 0
(-3375 4225);
DISPLAY 0.723404 (-3375 4225);
PAINT GREEN (-3375 4225);
DISPLAY INVISIBLE (-3375 4225);
FORCEPROP 1 LAST PART_NUMBER AJ051610U03
J 0
(-3725 5775);
DISPLAY 0.723404 (-3725 5775);
PAINT GREEN (-3725 5775);
DISPLAY INVISIBLE (-3725 5775);
FORCEADD TAP..1
(-2150 2925);
FORCEPROP 3 LASTPIN (-2200 2925) SIG_NAME P5E_CPU0_P0_TX_C_DP<0>
J 0
(-2190 2935);
DISPLAY 0.659574 (-2190 2935);
PAINT MONO (-2190 2935);
DISPLAY INVISIBLE (-2190 2935);
FORCEPROP 1 LASTPIN (-2200 2925) BN 0
J 0
(-2212 2933);
DISPLAY 0.680851 (-2212 2933);
PAINT GREEN (-2212 2933);
FORCEPROP 2 LAST CDS_LIB standard
J 0
(-2150 2925);
DISPLAY INVISIBLE (-2150 2925);
FORCEPROP 1 LAST BODY_TYPE PLUMBING
J 0
(-2150 2975);
DISPLAY 0.872340 (-2150 2975);
PAINT GREEN (-2150 2975);
DISPLAY INVISIBLE (-2150 2975);
FORCEPROP 1 LAST HDL_TAP TRUE
J 0
(-1825 2800);
DISPLAY 0.872340 (-1825 2800);
DISPLAY INVISIBLE (-1825 2800);
FORCEPROP 1 LAST PATH I40
J 0
(-2152 2925);
DISPLAY 0.872340 (-2152 2925);
PAINT GREEN (-2152 2925);
DISPLAY INVISIBLE (-2152 2925);
FORCEADD TAP..1
(-6975 3075);
FORCEPROP 3 LASTPIN (-7025 3075) SIG_NAME P5E_CPU0_P0_TX_C_DN<8>
J 0
(-7015 3085);
DISPLAY 0.659574 (-7015 3085);
PAINT MONO (-7015 3085);
DISPLAY INVISIBLE (-7015 3085);
FORCEPROP 1 LASTPIN (-7025 3075) BN 8
J 0
(-7037 3083);
DISPLAY 0.680851 (-7037 3083);
PAINT GREEN (-7037 3083);
FORCEPROP 2 LAST CDS_LIB standard
J 0
(-6975 3075);
DISPLAY INVISIBLE (-6975 3075);
FORCEPROP 1 LAST BODY_TYPE PLUMBING
J 0
(-6975 3125);
DISPLAY 0.872340 (-6975 3125);
PAINT GREEN (-6975 3125);
DISPLAY INVISIBLE (-6975 3125);
FORCEPROP 1 LAST HDL_TAP TRUE
J 0
(-6650 2950);
DISPLAY 0.872340 (-6650 2950);
DISPLAY INVISIBLE (-6650 2950);
FORCEPROP 1 LAST PATH I5
J 0
(-6977 3075);
DISPLAY 0.872340 (-6977 3075);
PAINT GREEN (-6977 3075);
DISPLAY INVISIBLE (-6977 3075);
FORCEADD TAP..1
(-6975 3425);
FORCEPROP 3 LASTPIN (-7025 3425) SIG_NAME P5E_CPU0_P0_TX_C_DN<9>
J 0
(-7015 3435);
DISPLAY 0.659574 (-7015 3435);
PAINT MONO (-7015 3435);
DISPLAY INVISIBLE (-7015 3435);
FORCEPROP 1 LASTPIN (-7025 3425) BN 9
J 0
(-7037 3433);
DISPLAY 0.680851 (-7037 3433);
PAINT GREEN (-7037 3433);
FORCEPROP 2 LAST CDS_LIB standard
J 0
(-6975 3425);
DISPLAY INVISIBLE (-6975 3425);
FORCEPROP 1 LAST BODY_TYPE PLUMBING
J 0
(-6975 3475);
DISPLAY 0.872340 (-6975 3475);
PAINT GREEN (-6975 3475);
DISPLAY INVISIBLE (-6975 3475);
FORCEPROP 1 LAST HDL_TAP TRUE
J 0
(-6650 3300);
DISPLAY 0.872340 (-6650 3300);
DISPLAY INVISIBLE (-6650 3300);
FORCEPROP 1 LAST PATH I6
J 0
(-6977 3425);
DISPLAY 0.872340 (-6977 3425);
PAINT GREEN (-6977 3425);
DISPLAY INVISIBLE (-6977 3425);
FORCEADD TAP..1
(-6975 3775);
FORCEPROP 3 LASTPIN (-7025 3775) SIG_NAME P5E_CPU0_P0_TX_C_DN<10>
J 0
(-7015 3785);
DISPLAY 0.659574 (-7015 3785);
PAINT MONO (-7015 3785);
DISPLAY INVISIBLE (-7015 3785);
FORCEPROP 1 LASTPIN (-7025 3775) BN 10
J 0
(-7037 3783);
DISPLAY 0.680851 (-7037 3783);
PAINT GREEN (-7037 3783);
FORCEPROP 2 LAST CDS_LIB standard
J 0
(-6975 3775);
DISPLAY INVISIBLE (-6975 3775);
FORCEPROP 1 LAST BODY_TYPE PLUMBING
J 0
(-6975 3825);
DISPLAY 0.872340 (-6975 3825);
PAINT GREEN (-6975 3825);
DISPLAY INVISIBLE (-6975 3825);
FORCEPROP 1 LAST HDL_TAP TRUE
J 0
(-6650 3650);
DISPLAY 0.872340 (-6650 3650);
DISPLAY INVISIBLE (-6650 3650);
FORCEPROP 1 LAST PATH I7
J 0
(-6977 3775);
DISPLAY 0.872340 (-6977 3775);
PAINT GREEN (-6977 3775);
DISPLAY INVISIBLE (-6977 3775);
FORCEADD TAP..1
(-6975 4125);
FORCEPROP 3 LASTPIN (-7025 4125) SIG_NAME P5E_CPU0_P0_TX_C_DN<11>
J 0
(-7015 4135);
DISPLAY 0.659574 (-7015 4135);
PAINT MONO (-7015 4135);
DISPLAY INVISIBLE (-7015 4135);
FORCEPROP 1 LASTPIN (-7025 4125) BN 11
J 0
(-7037 4133);
DISPLAY 0.680851 (-7037 4133);
PAINT GREEN (-7037 4133);
FORCEPROP 2 LAST CDS_LIB standard
J 0
(-6975 4125);
DISPLAY INVISIBLE (-6975 4125);
FORCEPROP 1 LAST BODY_TYPE PLUMBING
J 0
(-6975 4175);
DISPLAY 0.872340 (-6975 4175);
PAINT GREEN (-6975 4175);
DISPLAY INVISIBLE (-6975 4175);
FORCEPROP 1 LAST HDL_TAP TRUE
J 0
(-6650 4000);
DISPLAY 0.872340 (-6650 4000);
DISPLAY INVISIBLE (-6650 4000);
FORCEPROP 1 LAST PATH I8
J 0
(-6977 4125);
DISPLAY 0.872340 (-6977 4125);
PAINT GREEN (-6977 4125);
DISPLAY INVISIBLE (-6977 4125);
FORCEADD TAP..1
(-6975 4475);
FORCEPROP 3 LASTPIN (-7025 4475) SIG_NAME P5E_CPU0_P0_TX_C_DN<12>
J 0
(-7015 4485);
DISPLAY 0.659574 (-7015 4485);
PAINT MONO (-7015 4485);
DISPLAY INVISIBLE (-7015 4485);
FORCEPROP 1 LASTPIN (-7025 4475) BN 12
J 0
(-7037 4483);
DISPLAY 0.680851 (-7037 4483);
PAINT GREEN (-7037 4483);
FORCEPROP 2 LAST CDS_LIB standard
J 0
(-6975 4475);
DISPLAY INVISIBLE (-6975 4475);
FORCEPROP 1 LAST BODY_TYPE PLUMBING
J 0
(-6975 4525);
DISPLAY 0.872340 (-6975 4525);
PAINT GREEN (-6975 4525);
DISPLAY INVISIBLE (-6975 4525);
FORCEPROP 1 LAST HDL_TAP TRUE
J 0
(-6650 4350);
DISPLAY 0.872340 (-6650 4350);
DISPLAY INVISIBLE (-6650 4350);
FORCEPROP 1 LAST PATH I9
J 0
(-6977 4475);
DISPLAY 0.872340 (-6977 4475);
PAINT GREEN (-6977 4475);
DISPLAY INVISIBLE (-6977 4475);
FORCEADD QUANTA_TITLE_BLOCK_C..1
(0 0);
FORCEPROP 0 LAST CDS_CON_LAST_MODIFIED Thu Sep 14 16:12:49 2023
J 0
(-1885 15);
DISPLAY INVISIBLE (-1885 15);
FORCEPROP 1 LAST CUSTOM_TXT_CDS <CON_LAST_MODIFIED>
J 0
(-1885 15);
DISPLAY 0.978723 (-1885 15);
FORCEPROP 2 LAST CUSTOM_TXT_CDS <XR_PAGE_TITLE>
J 0
(-7890 5250);
DISPLAY 0.638298 (-7890 5250);
PAINT PINK (-7890 5250);
DISPLAY INVISIBLE (-7890 5250);
FORCEPROP 1 LAST CUSTOM_TXT_CDS <NAME_2>
J 0
(-3175 50);
FORCEPROP 1 LAST CUSTOM_TXT_CDS <NAME_1>
J 0
(-3175 175);
FORCEPROP 1 LAST CUSTOM_TXT_CDS <Q_NUMBER>
J 0
(-1403 103);
DISPLAY 1.212766 (-1403 103);
FORCEPROP 1 LAST CUSTOM_TXT_CDS <Q_PROJ>
J 0
(-2382 102);
DISPLAY 1.212766 (-2382 102);
FORCEPROP 1 LAST CUSTOM_TXT_CDS <Q_REV>
J 0
(-184 103);
DISPLAY 1.212766 (-184 103);
FORCEPROP 1 LAST CUSTOM_TXT_CDS <CON_PAGE_NUM> OF <CON_TOTAL_PAGES>
J 0
(-446 18);
DISPLAY 0.978723 (-446 18);
FORCEPROP 1 LAST Q_TITLE RETIMER_CPU0_P0(1)
J 0
(-9366 26);
DISPLAY 2.446809 (-9366 26);
PAINT GREEN (-9366 26);
FORCEPROP 2 LAST CDS_LIB pure_quanta
J 0
(0 0);
DISPLAY INVISIBLE (0 0);
FORCEPROP 1 LAST CDS_LMAN_SYM_OUTLINE -9475,6775,100,-125
J 0
(0 0);
DISPLAY 0.468085 (0 0);
PAINT GREEN (0 0);
DISPLAY INVISIBLE (0 0);
FORCEPROP 2 LAST PAGE_BORDER TRUE
J 0
(-7890 5250);
DISPLAY 0.638298 (-7890 5250);
PAINT PINK (-7890 5250);
DISPLAY INVISIBLE (-7890 5250);
FORCEPROP 2 LAST CDS_XR_PAGE_TITLE CR-273 : @T6G_MB_LIB.T6G(SCH_1):PAGE273
J 0
(-7890 5250);
DISPLAY 0.638298 (-7890 5250);
PAINT PINK (-7890 5250);
DISPLAY INVISIBLE (-7890 5250);
FORCEPROP 1 LAST Q_DEPT BU9
J 1
(-3763 49);
DISPLAY 1.957447 (-3763 49);
PAINT GREEN (-3763 49);
DISPLAY INVISIBLE (-3763 49);
FORCEPROP 1 LAST COMMENT_BODY TRUE
J 0
(12 -13);
DISPLAY 0.978723 (12 -13);
PAINT GREEN (12 -13);
DISPLAY INVISIBLE (12 -13);
WIRE 17 -1 (-2100 4700)(-2100 4350);
WIRE 17 -1 (-2100 5050)(-2100 4700);
WIRE 17 -1 (-2100 4000)(-2100 4350);
WIRE 17 -1 (-2100 4000)(-2100 3650);
WIRE 17 -1 (-2100 5400)(-2100 5050);
WIRE 17 -1 (-2100 5400)(-1200 5400);
FORCEPROP 2 LAST SIG_NAME P5E_CPU0_P0_TX_C_DP<7:0>
J 0
(-2035 5410);
DISPLAY 0.680851 (-2035 5410);
PAINT WHITE (-2035 5410);
WIRE 17 -1 (-6725 3350)(-6725 3000);
WIRE 17 -1 (-6725 3700)(-6725 3350);
WIRE 17 -1 (-6725 4050)(-6725 3700);
WIRE 17 -1 (-6725 4050)(-6725 4400);
WIRE 17 -1 (-6725 4850)(-6725 4400);
WIRE 17 -1 (-6725 5100)(-6725 4850);
WIRE 17 -1 (-6725 5450)(-6725 5100);
WIRE 17 -1 (-6725 5450)(-5825 5450);
FORCEPROP 2 LAST SIG_NAME P5E_CPU0_P0_TX_C_DP<15:8>
J 0
(-6660 5460);
DISPLAY 0.680851 (-6660 5460);
PAINT WHITE (-6660 5460);
WIRE 17 -1 (-6925 3450)(-6925 3100);
WIRE 17 -1 (-6925 3800)(-6925 3450);
WIRE 17 -1 (-6925 4150)(-6925 3800);
WIRE 17 -1 (-6925 4150)(-6925 4500);
WIRE 17 -1 (-6925 4750)(-6925 4500);
WIRE 17 -1 (-6925 5200)(-6925 4750);
WIRE 17 -1 (-6925 5550)(-6925 5200);
WIRE 17 -1 (-6925 5550)(-5825 5550);
FORCEPROP 2 LAST SIG_NAME P5E_CPU0_P0_TX_C_DN<15:8>
J 0
(-6660 5560);
DISPLAY 0.680851 (-6660 5560);
PAINT WHITE (-6660 5560);
WIRE 17 -1 (-2100 3400)(-2100 2950);
WIRE 17 -1 (-2100 3650)(-2100 3400);
WIRE 17 -1 (-2300 3300)(-2300 3050);
WIRE 17 -1 (-2300 3750)(-2300 3300);
WIRE 17 -1 (-2300 4100)(-2300 3750);
WIRE 17 -1 (-2300 4100)(-2300 4450);
WIRE 17 -1 (-2300 4800)(-2300 4450);
WIRE 17 -1 (-2300 5150)(-2300 4800);
WIRE 17 -1 (-2300 5500)(-2300 5150);
WIRE 17 -1 (-2300 5500)(-1200 5500);
FORCEPROP 2 LAST SIG_NAME P5E_CPU0_P0_TX_C_DN<7:0>
J 0
(-2035 5510);
DISPLAY 0.680851 (-2035 5510);
PAINT WHITE (-2035 5510);
WIRE 16 -1 (-7550 4825)(-6825 4825);
WIRE 16 -1 (-7550 4725)(-7025 4725);
WIRE 16 -1 (-7550 5075)(-6825 5075);
WIRE 16 -1 (-2925 5375)(-2200 5375);
WIRE 16 -1 (-2925 5125)(-2400 5125);
WIRE 16 -1 (-2925 5025)(-2200 5025);
WIRE 16 -1 (-2925 4425)(-2400 4425);
WIRE 16 -1 (-2925 3725)(-2400 3725);
WIRE 16 -1 (-2925 4075)(-2400 4075);
WIRE 16 -1 (-2400 3275)(-2925 3275);
WIRE 16 -1 (-2925 5475)(-2400 5475);
WIRE 16 -1 (-2925 4775)(-2400 4775);
WIRE 16 -1 (-2925 3025)(-2400 3025);
WIRE 16 -1 (-2925 4675)(-2200 4675);
WIRE 16 -1 (-7550 4025)(-6825 4025);
WIRE 16 -1 (-7550 4125)(-7025 4125);
WIRE 16 -1 (-7550 5525)(-7025 5525);
WIRE 16 -1 (-7550 5425)(-6825 5425);
WIRE 16 -1 (-2925 3625)(-2200 3625);
WIRE 16 -1 (-2925 3975)(-2200 3975);
WIRE 16 -1 (-2925 3375)(-2200 3375);
WIRE 16 -1 (-2925 2925)(-2200 2925);
WIRE 16 -1 (-7550 3775)(-7025 3775);
WIRE 16 -1 (-7550 3425)(-7025 3425);
WIRE 16 -1 (-7550 4475)(-7025 4475);
WIRE 16 -1 (-7550 5175)(-7025 5175);
WIRE 16 -1 (-7550 3075)(-7025 3075);
WIRE 16 -1 (-7550 3325)(-6825 3325);
WIRE 16 -1 (-7550 3675)(-6825 3675);
WIRE 16 -1 (-7550 4375)(-6825 4375);
WIRE 16 -1 (-7550 2975)(-6825 2975);
WIRE 16 -1 (-2925 4325)(-2200 4325);
FORCENOTE
P/N SWAP
(-6625 5350) 0;
DISPLAY LEFT (-6625 5350);
DISPLAY 1.021277 (-6625 5350);
FORCENOTE
P/N SWAP
(-2025 5300) 0;
DISPLAY LEFT (-2025 5300);
DISPLAY 1.021277 (-2025 5300);
FORCENOTE
CPU TO RETIMER
(-8425 2125) 0;
DISPLAY LEFT (-8425 2125);
DISPLAY 3.148936 (-8425 2125);
FORCENOTE
CPU TO RETIMER
(-3825 2125) 0;
DISPLAY LEFT (-3825 2125);
DISPLAY 3.148936 (-3825 2125);
FORCENOTE
P5E_CPU0_P0_TX_C_DP/DN<0-15> LANE REVERSAL
(-9100 6350) 0;
DISPLAY LEFT (-9100 6350);
DISPLAY 2.000000 (-9100 6350);
FORCENOTE
P/N SWAP
(-6625 5075) 0;
DISPLAY LEFT (-6625 5075);
DISPLAY 1.021277 (-6625 5075);
FORCENOTE
P/N SWAP
(-6625 2975) 0;
DISPLAY LEFT (-6625 2975);
DISPLAY 1.021277 (-6625 2975);
FORCENOTE
P/N SWAP
(-1975 2925) 0;
DISPLAY LEFT (-1975 2925);
DISPLAY 1.021277 (-1975 2925);
FORCENOTE
P/N SWAP
(-1950 3675) 0;
DISPLAY LEFT (-1950 3675);
DISPLAY 1.021277 (-1950 3675);
FORCENOTE
P/N SWAP
(-1975 4050) 0;
DISPLAY LEFT (-1975 4050);
DISPLAY 1.021277 (-1975 4050);
FORCENOTE
P/N SWAP
(-1975 4375) 0;
DISPLAY LEFT (-1975 4375);
DISPLAY 1.021277 (-1975 4375);
FORCENOTE
P/N SWAP
(-2000 4700) 0;
DISPLAY LEFT (-2000 4700);
DISPLAY 1.021277 (-2000 4700);
FORCENOTE
P/N SWAP
(-2025 5050) 0;
DISPLAY LEFT (-2025 5050);
DISPLAY 1.021277 (-2025 5050);
FORCENOTE
P/N SWAP
(-6600 3325) 0;
DISPLAY LEFT (-6600 3325);
DISPLAY 1.021277 (-6600 3325);
FORCENOTE
P/N SWAP
(-6625 3700) 0;
DISPLAY LEFT (-6625 3700);
DISPLAY 1.021277 (-6625 3700);
FORCENOTE
P/N SWAP
(-6600 4025) 0;
DISPLAY LEFT (-6600 4025);
DISPLAY 1.021277 (-6600 4025);
FORCENOTE
P/N SWAP
(-6625 4400) 0;
DISPLAY LEFT (-6625 4400);
DISPLAY 1.021277 (-6625 4400);
QUIT
